(kicad_pcb
	(version 20260206)
	(generator "pcbnew")
	(generator_version "10.0")
	(general
		(thickness 1.6)
		(legacy_teardrops no)
	)
	(paper "A4")
	(title_block
		(title "01162023_DA0F0TEBIF0_F0T_Expander_BD_F_brd_V02_OCP.brd")
		(comment 1 "Grand Teton / footprints 2663-2670 of 9728")
	)
	(layers
		(0 "F.Cu" signal "TOP")
		(4 "In1.Cu" signal "GND")
		(6 "In2.Cu" signal "VCC")
		(8 "In3.Cu" signal "VCC1")
		(10 "In4.Cu" signal "GND1")
		(12 "In5.Cu" signal "IN1")
		(14 "In6.Cu" signal "GND2")
		(16 "In7.Cu" signal "IN2")
		(18 "In8.Cu" signal "GND3")
		(20 "In9.Cu" signal "IN3")
		(22 "In10.Cu" signal "GND4")
		(24 "In11.Cu" signal "IN4")
		(26 "In12.Cu" signal "GND5")
		(28 "In13.Cu" signal "IN5")
		(30 "In14.Cu" signal "GND6")
		(32 "In15.Cu" signal "IN6")
		(34 "In16.Cu" signal "GND7")
		(2 "B.Cu" signal "BOTTOM")
		(9 "F.Adhes" user "F.Adhesive")
		(11 "B.Adhes" user "B.Adhesive")
		(13 "F.Paste" user "Package Geometry/Pastemask Top")
		(15 "B.Paste" user "Package Geometry/Pastemask Bottom")
		(5 "F.SilkS" user "Ref Des/Silkscreen Top")
		(7 "B.SilkS" user "Ref Des/Silkscreen Bottom")
		(1 "F.Mask" user "Board Geometry/Soldermask Top")
		(3 "B.Mask" user "Board Geometry/Soldermask Bottom")
		(17 "Dwgs.User" user "User.Drawings")
		(19 "Cmts.User" user "User.Comments")
		(21 "Eco1.User" user "User.Eco1")
		(23 "Eco2.User" user "User.Eco2")
		(25 "Edge.Cuts" user "Board Geometry/Outline")
		(27 "Margin" user)
		(31 "F.CrtYd" user "Package Geometry/Place Bound Top")
		(29 "B.CrtYd" user "Package Geometry/Place Bound Bottom")
		(35 "F.Fab" user "Ref Des/Assembly Top")
		(33 "B.Fab" user "Ref Des/Assembly Bottom")
	)
	(footprint ""
		(layer "F.Cu")
		(at 150.602442 -250.070874 -90)
		(property "Reference" "R1280"
			(at 0 0 270)
			(layer "F.SilkS")
			(hide yes)
			(effects
				(font
					(size 1.27 1.27)
				)
			)
		)
		(property "Value" ""
			(at 0 0 270)
			(layer "F.Fab")
			(effects
				(font
					(size 1.27 1.27)
				)
			)
		)
		(duplicate_pad_numbers_are_jumpers no)
		(fp_line
			(start -0.7874 0.4064)
			(end -0.7874 -0.4064)
			(stroke
				(width 0.1524)
				(type default)
			)
			(layer "F.SilkS")
		)
		(fp_line
			(start 0.7874 0.4064)
			(end -0.7874 0.4064)
			(stroke
				(width 0.1524)
				(type default)
			)
			(layer "F.SilkS")
		)
		(fp_line
			(start -0.7874 -0.4064)
			(end 0.7874 -0.4064)
			(stroke
				(width 0.1524)
				(type default)
			)
			(layer "F.SilkS")
		)
		(fp_line
			(start 0.7874 -0.4064)
			(end 0.7874 0.4064)
			(stroke
				(width 0.1524)
				(type default)
			)
			(layer "F.SilkS")
		)
		(fp_line
			(start -0.67945 0.3048)
			(end -0.67945 -0.305054)
			(stroke
				(width 0.1)
				(type default)
			)
			(layer "F.Fab")
		)
		(fp_line
			(start -0.12065 0.3048)
			(end -0.67945 0.3048)
			(stroke
				(width 0.1)
				(type default)
			)
			(layer "F.Fab")
		)
		(fp_line
			(start 0.120396 0.3048)
			(end 0.120396 0.2794)
			(stroke
				(width 0.1)
				(type default)
			)
			(layer "F.Fab")
		)
		(fp_line
			(start 0.67945 0.3048)
			(end 0.120396 0.3048)
			(stroke
				(width 0.1)
				(type default)
			)
			(layer "F.Fab")
		)
		(fp_line
			(start -0.12065 0.2794)
			(end -0.12065 0.3048)
			(stroke
				(width 0.1)
				(type default)
			)
			(layer "F.Fab")
		)
		(fp_line
			(start 0.120396 0.2794)
			(end -0.12065 0.2794)
			(stroke
				(width 0.1)
				(type default)
			)
			(layer "F.Fab")
		)
		(fp_line
			(start -0.12065 -0.2794)
			(end 0.12065 -0.2794)
			(stroke
				(width 0.1)
				(type default)
			)
			(layer "F.Fab")
		)
		(fp_line
			(start 0.12065 -0.2794)
			(end 0.12065 -0.3048)
			(stroke
				(width 0.1)
				(type default)
			)
			(layer "F.Fab")
		)
		(fp_line
			(start 0.12065 -0.3048)
			(end 0.67945 -0.3048)
			(stroke
				(width 0.1)
				(type default)
			)
			(layer "F.Fab")
		)
		(fp_line
			(start 0.67945 -0.3048)
			(end 0.67945 0.3048)
			(stroke
				(width 0.1)
				(type default)
			)
			(layer "F.Fab")
		)
		(fp_line
			(start -0.67945 -0.305054)
			(end -0.12065 -0.305054)
			(stroke
				(width 0.1)
				(type default)
			)
			(layer "F.Fab")
		)
		(fp_line
			(start -0.12065 -0.305054)
			(end -0.12065 -0.2794)
			(stroke
				(width 0.1)
				(type default)
			)
			(layer "F.Fab")
		)
		(pad "1" smd circle
			(at -0.40005 0 270)
			(size 0 0)
			(layers "F.Cu" "F.Mask" "F.Paste")
			(net "PEX1_MODE_SEL11")
		)
		(pad "2" smd circle
			(at 0.40005 0 270)
			(size 0 0)
			(layers "F.Cu" "F.Mask" "F.Paste")
			(net "P1V8_PEX")
		)
	)
	(footprint ""
		(layer "F.Cu")
		(at 386.70738 -350.098614 90)
		(property "Reference" "C776"
			(at 0 0 90)
			(layer "F.SilkS")
			(hide yes)
			(effects
				(font
					(size 1.27 1.27)
				)
			)
		)
		(property "Value" ""
			(at 0 0 90)
			(layer "F.Fab")
			(effects
				(font
					(size 1.27 1.27)
				)
			)
		)
		(duplicate_pad_numbers_are_jumpers no)
		(fp_line
			(start 0.299974 -0.150114)
			(end 0.299974 0.150114)
			(stroke
				(width 0.1)
				(type default)
			)
			(layer "F.Fab")
		)
		(fp_line
			(start -0.299974 -0.150114)
			(end 0.299974 -0.150114)
			(stroke
				(width 0.1)
				(type default)
			)
			(layer "F.Fab")
		)
		(fp_line
			(start 0.299974 0.150114)
			(end -0.299974 0.150114)
			(stroke
				(width 0.1)
				(type default)
			)
			(layer "F.Fab")
		)
		(fp_line
			(start -0.299974 0.150114)
			(end -0.299974 -0.150114)
			(stroke
				(width 0.1)
				(type default)
			)
			(layer "F.Fab")
		)
		(pad "1" smd rect
			(at -0.2667 0 90)
			(size 0.3048 0.381)
			(layers "F.Cu" "F.Mask" "F.Paste")
			(net "P5E_PEX3_STN6_TX_DP<104>")
		)
		(pad "2" smd rect
			(at 0.2667 0 90)
			(size 0.3048 0.381)
			(layers "F.Cu" "F.Mask" "F.Paste")
			(net "P5E_PEX3_STN6_TX_C_DP<104>")
		)
	)
	(footprint ""
		(layer "F.Cu")
		(at 326.012556 -197.250304)
		(property "Reference" "R4245"
			(at 0 0 0)
			(layer "F.SilkS")
			(hide yes)
			(effects
				(font
					(size 1.27 1.27)
				)
			)
		)
		(property "Value" ""
			(at 0 0 0)
			(layer "F.Fab")
			(effects
				(font
					(size 1.27 1.27)
				)
			)
		)
		(duplicate_pad_numbers_are_jumpers no)
		(fp_line
			(start -0.7874 -0.4064)
			(end 0.7874 -0.4064)
			(stroke
				(width 0.1524)
				(type default)
			)
			(layer "F.SilkS")
		)
		(fp_line
			(start -0.7874 0.4064)
			(end -0.7874 -0.4064)
			(stroke
				(width 0.1524)
				(type default)
			)
			(layer "F.SilkS")
		)
		(fp_line
			(start 0.7874 -0.4064)
			(end 0.7874 0.4064)
			(stroke
				(width 0.1524)
				(type default)
			)
			(layer "F.SilkS")
		)
		(fp_line
			(start 0.7874 0.4064)
			(end -0.7874 0.4064)
			(stroke
				(width 0.1524)
				(type default)
			)
			(layer "F.SilkS")
		)
		(fp_line
			(start -0.67945 -0.305054)
			(end -0.12065 -0.305054)
			(stroke
				(width 0.1)
				(type default)
			)
			(layer "F.Fab")
		)
		(fp_line
			(start -0.67945 0.3048)
			(end -0.67945 -0.305054)
			(stroke
				(width 0.1)
				(type default)
			)
			(layer "F.Fab")
		)
		(fp_line
			(start -0.12065 -0.305054)
			(end -0.12065 -0.2794)
			(stroke
				(width 0.1)
				(type default)
			)
			(layer "F.Fab")
		)
		(fp_line
			(start -0.12065 -0.2794)
			(end 0.12065 -0.2794)
			(stroke
				(width 0.1)
				(type default)
			)
			(layer "F.Fab")
		)
		(fp_line
			(start -0.12065 0.2794)
			(end -0.12065 0.3048)
			(stroke
				(width 0.1)
				(type default)
			)
			(layer "F.Fab")
		)
		(fp_line
			(start -0.12065 0.3048)
			(end -0.67945 0.3048)
			(stroke
				(width 0.1)
				(type default)
			)
			(layer "F.Fab")
		)
		(fp_line
			(start 0.120396 0.2794)
			(end -0.12065 0.2794)
			(stroke
				(width 0.1)
				(type default)
			)
			(layer "F.Fab")
		)
		(fp_line
			(start 0.120396 0.3048)
			(end 0.120396 0.2794)
			(stroke
				(width 0.1)
				(type default)
			)
			(layer "F.Fab")
		)
		(fp_line
			(start 0.12065 -0.3048)
			(end 0.67945 -0.3048)
			(stroke
				(width 0.1)
				(type default)
			)
			(layer "F.Fab")
		)
		(fp_line
			(start 0.12065 -0.2794)
			(end 0.12065 -0.3048)
			(stroke
				(width 0.1)
				(type default)
			)
			(layer "F.Fab")
		)
		(fp_line
			(start 0.67945 -0.3048)
			(end 0.67945 0.3048)
			(stroke
				(width 0.1)
				(type default)
			)
			(layer "F.Fab")
		)
		(fp_line
			(start 0.67945 0.3048)
			(end 0.120396 0.3048)
			(stroke
				(width 0.1)
				(type default)
			)
			(layer "F.Fab")
		)
		(pad "1" smd circle
			(at -0.40005 0)
			(size 0 0)
			(layers "F.Cu" "F.Mask" "F.Paste")
			(net "GND")
		)
		(pad "2" smd circle
			(at 0.40005 0)
			(size 0 0)
			(layers "F.Cu" "F.Mask" "F.Paste")
			(net "IOEXP_DBV2_A1")
		)
	)
	(footprint ""
		(layer "F.Cu")
		(at 163.047426 -19.33956)
		(property "Reference" "C3912"
			(at 0 0 0)
			(layer "F.SilkS")
			(hide yes)
			(effects
				(font
					(size 1.27 1.27)
				)
			)
		)
		(property "Value" ""
			(at 0 0 0)
			(layer "F.Fab")
			(effects
				(font
					(size 1.27 1.27)
				)
			)
		)
		(duplicate_pad_numbers_are_jumpers no)
		(fp_line
			(start -0.7874 -0.4064)
			(end 0.7874 -0.4064)
			(stroke
				(width 0.1524)
				(type default)
			)
			(layer "F.SilkS")
		)
		(fp_line
			(start -0.7874 0.4064)
			(end -0.7874 -0.4064)
			(stroke
				(width 0.1524)
				(type default)
			)
			(layer "F.SilkS")
		)
		(fp_line
			(start 0.7874 -0.4064)
			(end 0.7874 0.4064)
			(stroke
				(width 0.1524)
				(type default)
			)
			(layer "F.SilkS")
		)
		(fp_line
			(start 0.7874 0.4064)
			(end -0.7874 0.4064)
			(stroke
				(width 0.1524)
				(type default)
			)
			(layer "F.SilkS")
		)
		(fp_line
			(start -0.67945 -0.305054)
			(end -0.12065 -0.305054)
			(stroke
				(width 0.1)
				(type default)
			)
			(layer "F.Fab")
		)
		(fp_line
			(start -0.67945 0.3048)
			(end -0.67945 -0.305054)
			(stroke
				(width 0.1)
				(type default)
			)
			(layer "F.Fab")
		)
		(fp_line
			(start -0.12065 -0.305054)
			(end -0.12065 -0.2794)
			(stroke
				(width 0.1)
				(type default)
			)
			(layer "F.Fab")
		)
		(fp_line
			(start -0.12065 -0.2794)
			(end 0.12065 -0.2794)
			(stroke
				(width 0.1)
				(type default)
			)
			(layer "F.Fab")
		)
		(fp_line
			(start -0.12065 0.2794)
			(end -0.12065 0.3048)
			(stroke
				(width 0.1)
				(type default)
			)
			(layer "F.Fab")
		)
		(fp_line
			(start -0.12065 0.3048)
			(end -0.67945 0.3048)
			(stroke
				(width 0.1)
				(type default)
			)
			(layer "F.Fab")
		)
		(fp_line
			(start 0.120396 0.2794)
			(end -0.12065 0.2794)
			(stroke
				(width 0.1)
				(type default)
			)
			(layer "F.Fab")
		)
		(fp_line
			(start 0.120396 0.3048)
			(end 0.120396 0.2794)
			(stroke
				(width 0.1)
				(type default)
			)
			(layer "F.Fab")
		)
		(fp_line
			(start 0.12065 -0.3048)
			(end 0.67945 -0.3048)
			(stroke
				(width 0.1)
				(type default)
			)
			(layer "F.Fab")
		)
		(fp_line
			(start 0.12065 -0.2794)
			(end 0.12065 -0.3048)
			(stroke
				(width 0.1)
				(type default)
			)
			(layer "F.Fab")
		)
		(fp_line
			(start 0.67945 -0.3048)
			(end 0.67945 0.3048)
			(stroke
				(width 0.1)
				(type default)
			)
			(layer "F.Fab")
		)
		(fp_line
			(start 0.67945 0.3048)
			(end 0.120396 0.3048)
			(stroke
				(width 0.1)
				(type default)
			)
			(layer "F.Fab")
		)
		(pad "1" smd circle
			(at -0.40005 0)
			(size 0 0)
			(layers "F.Cu" "F.Mask" "F.Paste")
			(net "P12V_SSD5")
		)
		(pad "2" smd circle
			(at 0.40005 0)
			(size 0 0)
			(layers "F.Cu" "F.Mask" "F.Paste")
			(net "GND")
		)
	)
	(footprint ""
		(layer "F.Cu")
		(at 343.027 -234.061 -90)
		(property "Reference" "R3539"
			(at 0 0 270)
			(layer "F.SilkS")
			(hide yes)
			(effects
				(font
					(size 1.27 1.27)
				)
			)
		)
		(property "Value" ""
			(at 0 0 270)
			(layer "F.Fab")
			(effects
				(font
					(size 1.27 1.27)
				)
			)
		)
		(duplicate_pad_numbers_are_jumpers no)
		(fp_line
			(start -0.7874 0.4064)
			(end -0.7874 -0.4064)
			(stroke
				(width 0.1524)
				(type default)
			)
			(layer "F.SilkS")
		)
		(fp_line
			(start 0.7874 0.4064)
			(end -0.7874 0.4064)
			(stroke
				(width 0.1524)
				(type default)
			)
			(layer "F.SilkS")
		)
		(fp_line
			(start -0.7874 -0.4064)
			(end 0.7874 -0.4064)
			(stroke
				(width 0.1524)
				(type default)
			)
			(layer "F.SilkS")
		)
		(fp_line
			(start 0.7874 -0.4064)
			(end 0.7874 0.4064)
			(stroke
				(width 0.1524)
				(type default)
			)
			(layer "F.SilkS")
		)
		(fp_line
			(start -0.67945 0.3048)
			(end -0.67945 -0.305054)
			(stroke
				(width 0.1)
				(type default)
			)
			(layer "F.Fab")
		)
		(fp_line
			(start -0.12065 0.3048)
			(end -0.67945 0.3048)
			(stroke
				(width 0.1)
				(type default)
			)
			(layer "F.Fab")
		)
		(fp_line
			(start 0.120396 0.3048)
			(end 0.120396 0.2794)
			(stroke
				(width 0.1)
				(type default)
			)
			(layer "F.Fab")
		)
		(fp_line
			(start 0.67945 0.3048)
			(end 0.120396 0.3048)
			(stroke
				(width 0.1)
				(type default)
			)
			(layer "F.Fab")
		)
		(fp_line
			(start -0.12065 0.2794)
			(end -0.12065 0.3048)
			(stroke
				(width 0.1)
				(type default)
			)
			(layer "F.Fab")
		)
		(fp_line
			(start 0.120396 0.2794)
			(end -0.12065 0.2794)
			(stroke
				(width 0.1)
				(type default)
			)
			(layer "F.Fab")
		)
		(fp_line
			(start -0.12065 -0.2794)
			(end 0.12065 -0.2794)
			(stroke
				(width 0.1)
				(type default)
			)
			(layer "F.Fab")
		)
		(fp_line
			(start 0.12065 -0.2794)
			(end 0.12065 -0.3048)
			(stroke
				(width 0.1)
				(type default)
			)
			(layer "F.Fab")
		)
		(fp_line
			(start 0.12065 -0.3048)
			(end 0.67945 -0.3048)
			(stroke
				(width 0.1)
				(type default)
			)
			(layer "F.Fab")
		)
		(fp_line
			(start 0.67945 -0.3048)
			(end 0.67945 0.3048)
			(stroke
				(width 0.1)
				(type default)
			)
			(layer "F.Fab")
		)
		(fp_line
			(start -0.67945 -0.305054)
			(end -0.12065 -0.305054)
			(stroke
				(width 0.1)
				(type default)
			)
			(layer "F.Fab")
		)
		(fp_line
			(start -0.12065 -0.305054)
			(end -0.12065 -0.2794)
			(stroke
				(width 0.1)
				(type default)
			)
			(layer "F.Fab")
		)
		(pad "1" smd circle
			(at -0.40005 0 270)
			(size 0 0)
			(layers "F.Cu" "F.Mask" "F.Paste")
			(net "RST_SSD3_PERST_R_N")
		)
		(pad "2" smd circle
			(at 0.40005 0 270)
			(size 0 0)
			(layers "F.Cu" "F.Mask" "F.Paste")
			(net "RST_SSD3_PERST_N")
		)
	)
	(footprint ""
		(layer "F.Cu")
		(at 363.474 -194.691)
		(property "Reference" "R4668"
			(at 0 0 0)
			(layer "F.SilkS")
			(hide yes)
			(effects
				(font
					(size 1.27 1.27)
				)
			)
		)
		(property "Value" ""
			(at 0 0 0)
			(layer "F.Fab")
			(effects
				(font
					(size 1.27 1.27)
				)
			)
		)
		(duplicate_pad_numbers_are_jumpers no)
		(fp_line
			(start -0.7874 -0.4064)
			(end 0.7874 -0.4064)
			(stroke
				(width 0.1524)
				(type default)
			)
			(layer "F.SilkS")
		)
		(fp_line
			(start -0.7874 0.4064)
			(end -0.7874 -0.4064)
			(stroke
				(width 0.1524)
				(type default)
			)
			(layer "F.SilkS")
		)
		(fp_line
			(start 0.7874 -0.4064)
			(end 0.7874 0.4064)
			(stroke
				(width 0.1524)
				(type default)
			)
			(layer "F.SilkS")
		)
		(fp_line
			(start 0.7874 0.4064)
			(end -0.7874 0.4064)
			(stroke
				(width 0.1524)
				(type default)
			)
			(layer "F.SilkS")
		)
		(fp_line
			(start -0.67945 -0.305054)
			(end -0.12065 -0.305054)
			(stroke
				(width 0.1)
				(type default)
			)
			(layer "F.Fab")
		)
		(fp_line
			(start -0.67945 0.3048)
			(end -0.67945 -0.305054)
			(stroke
				(width 0.1)
				(type default)
			)
			(layer "F.Fab")
		)
		(fp_line
			(start -0.12065 -0.305054)
			(end -0.12065 -0.2794)
			(stroke
				(width 0.1)
				(type default)
			)
			(layer "F.Fab")
		)
		(fp_line
			(start -0.12065 -0.2794)
			(end 0.12065 -0.2794)
			(stroke
				(width 0.1)
				(type default)
			)
			(layer "F.Fab")
		)
		(fp_line
			(start -0.12065 0.2794)
			(end -0.12065 0.3048)
			(stroke
				(width 0.1)
				(type default)
			)
			(layer "F.Fab")
		)
		(fp_line
			(start -0.12065 0.3048)
			(end -0.67945 0.3048)
			(stroke
				(width 0.1)
				(type default)
			)
			(layer "F.Fab")
		)
		(fp_line
			(start 0.120396 0.2794)
			(end -0.12065 0.2794)
			(stroke
				(width 0.1)
				(type default)
			)
			(layer "F.Fab")
		)
		(fp_line
			(start 0.120396 0.3048)
			(end 0.120396 0.2794)
			(stroke
				(width 0.1)
				(type default)
			)
			(layer "F.Fab")
		)
		(fp_line
			(start 0.12065 -0.3048)
			(end 0.67945 -0.3048)
			(stroke
				(width 0.1)
				(type default)
			)
			(layer "F.Fab")
		)
		(fp_line
			(start 0.12065 -0.2794)
			(end 0.12065 -0.3048)
			(stroke
				(width 0.1)
				(type default)
			)
			(layer "F.Fab")
		)
		(fp_line
			(start 0.67945 -0.3048)
			(end 0.67945 0.3048)
			(stroke
				(width 0.1)
				(type default)
			)
			(layer "F.Fab")
		)
		(fp_line
			(start 0.67945 0.3048)
			(end 0.120396 0.3048)
			(stroke
				(width 0.1)
				(type default)
			)
			(layer "F.Fab")
		)
		(pad "1" smd circle
			(at -0.40005 0)
			(size 0 0)
			(layers "F.Cu" "F.Mask" "F.Paste")
			(net "P3V3_AUX")
		)
		(pad "2" smd circle
			(at 0.40005 0)
			(size 0 0)
			(layers "F.Cu" "F.Mask" "F.Paste")
			(net "RST_PEX_SSD5_PERST_R_N")
		)
	)
	(footprint ""
		(layer "F.Cu")
		(at 77.806042 -343.952322 90)
		(property "Reference" "C114"
			(at 0 0 90)
			(layer "F.SilkS")
			(hide yes)
			(effects
				(font
					(size 1.27 1.27)
				)
			)
		)
		(property "Value" ""
			(at 0 0 90)
			(layer "F.Fab")
			(effects
				(font
					(size 1.27 1.27)
				)
			)
		)
		(duplicate_pad_numbers_are_jumpers no)
		(fp_line
			(start 0.299974 -0.150114)
			(end 0.299974 0.150114)
			(stroke
				(width 0.1)
				(type default)
			)
			(layer "F.Fab")
		)
		(fp_line
			(start -0.299974 -0.150114)
			(end 0.299974 -0.150114)
			(stroke
				(width 0.1)
				(type default)
			)
			(layer "F.Fab")
		)
		(fp_line
			(start 0.299974 0.150114)
			(end -0.299974 0.150114)
			(stroke
				(width 0.1)
				(type default)
			)
			(layer "F.Fab")
		)
		(fp_line
			(start -0.299974 0.150114)
			(end -0.299974 -0.150114)
			(stroke
				(width 0.1)
				(type default)
			)
			(layer "F.Fab")
		)
		(pad "1" smd rect
			(at -0.2667 0 90)
			(size 0.3048 0.381)
			(layers "F.Cu" "F.Mask" "F.Paste")
			(net "P5E_PEX0_STN5_TX_DN<87>")
		)
		(pad "2" smd rect
			(at 0.2667 0 90)
			(size 0.3048 0.381)
			(layers "F.Cu" "F.Mask" "F.Paste")
			(net "P5E_PEX0_STN5_TX_C_DN<87>")
		)
	)
	(footprint ""
		(layer "F.Cu")
		(at 34.851848 -356.244906 90)
		(property "Reference" "C175"
			(at 0 0 90)
			(layer "F.SilkS")
			(hide yes)
			(effects
				(font
					(size 1.27 1.27)
				)
			)
		)
		(property "Value" ""
			(at 0 0 90)
			(layer "F.Fab")
			(effects
				(font
					(size 1.27 1.27)
				)
			)
		)
		(duplicate_pad_numbers_are_jumpers no)
		(fp_line
			(start 0.299974 -0.150114)
			(end 0.299974 0.150114)
			(stroke
				(width 0.1)
				(type default)
			)
			(layer "F.Fab")
		)
		(fp_line
			(start -0.299974 -0.150114)
			(end 0.299974 -0.150114)
			(stroke
				(width 0.1)
				(type default)
			)
			(layer "F.Fab")
		)
		(fp_line
			(start 0.299974 0.150114)
			(end -0.299974 0.150114)
			(stroke
				(width 0.1)
				(type default)
			)
			(layer "F.Fab")
		)
		(fp_line
			(start -0.299974 0.150114)
			(end -0.299974 -0.150114)
			(stroke
				(width 0.1)
				(type default)
			)
			(layer "F.Fab")
		)
		(pad "1" smd rect
			(at -0.2667 0 90)
			(size 0.3048 0.381)
			(layers "F.Cu" "F.Mask" "F.Paste")
			(net "P5E_PEX0_STN7_TX_DP<120>")
		)
		(pad "2" smd rect
			(at 0.2667 0 90)
			(size 0.3048 0.381)
			(layers "F.Cu" "F.Mask" "F.Paste")
			(net "P5E_PEX0_STN7_TX_C_DP<120>")
		)
	)
)
